# BASEBOARD_FAB2 (Tioga Pass) — schematic netlist excerpt (pin names and nets, part order shuffled) for the footprints in the layout excerpt that follows; sources: Cadence DE-HDL packaged netlist, KiCad conversion of Wiwynn_Tioga_Pass_MB.brd

J6T1  SCONN288_H44441003  SCONN  pkg PIP  page 44
  \12v\(1)  = P12V_NVDIMM_ABC
  VSS(93)  = GND
  DQ(4)  = M_A_DQ<4>
  VSS(92)  = GND
  DQ(0)  = M_A_DQ<0>
  VSS(91)  = GND
  DQS9P  = M_A_DQS_DP<9>
  DQS9N  = M_A_DQS_DN<9>
  VSS(90)  = GND
  DQ(6)  = M_A_DQ<6>
  VSS(89)  = GND
  DQ(2)  = M_A_DQ<2>
  VSS(88)  = GND
  DQ(12)  = M_A_DQ<12>
  VSS(87)  = GND
  DQ(8)  = M_A_DQ<8>
  VSS(86)  = GND
  DQS10P  = M_A_DQS_DP<10>
  DQS10N  = M_A_DQS_DN<10>
  VSS(85)  = GND
  DQ(14)  = M_A_DQ<14>
  VSS(84)  = GND
  DQ(10)  = M_A_DQ<10>
  VSS(83)  = GND
  DQ(20)  = M_A_DQ<20>
  VSS(82)  = GND
  DQ(16)  = M_A_DQ<16>
  VSS(81)  = GND
  DQS11P  = M_A_DQS_DP<11>
  DQS11N  = M_A_DQS_DN<11>
  VSS(80)  = GND
  DQ(22)  = M_A_DQ<22>
  VSS(79)  = GND
  DQ(18)  = M_A_DQ<18>
  VSS(78)  = GND
  DQ(28)  = M_A_DQ<28>
  VSS(77)  = GND
  DQ(24)  = M_A_DQ<24>
  VSS(76)  = GND
  DQS12P  = M_A_DQS_DP<12>
  DQS12N  = M_A_DQS_DN<12>
  VSS(75)  = GND
  DQ(30)  = M_A_DQ<30>
  VSS(74)  = GND
  DQ(26)  = M_A_DQ<26>
  VSS(73)  = GND
  CB(4)  = M_A_ECC<4>
  VSS(72)  = GND
  CB(0)  = M_A_ECC<0>
  VSS(71)  = GND
  DQS17P  = M_A_DQS_DP<17>
  DQS17N  = M_A_DQS_DN<17>
  VSS(70)  = GND
  CB(6)  = M_A_ECC<6>
  VSS(69)  = GND
  CB(2)  = M_A_ECC<2>
  VSS(68)  = GND
  RESET_N  = M_ABC_RST_N
  VDD(25)  = PVDDQ_ABC
  CKE(0)  = M_A_CKE<2>
  VDD(24)  = PVDDQ_ABC
  ACT_N  = M_A_ACT_N
  BG(0)  = M_A_BG<0>
  VDD(23)  = PVDDQ_ABC
  A12  = M_A_MA<12>
  A9  = M_A_MA<9>
  VDD(22)  = PVDDQ_ABC
  A8  = M_A_MA<8>
  A6  = M_A_MA<6>
  VDD(21)  = PVDDQ_ABC
  A3  = M_A_MA<3>
  A1  = M_A_MA<1>
  VDD(20)  = PVDDQ_ABC
  CK0P  = M_A_CLK_DP<2>
  CK0N  = M_A_CLK_DN<2>
  VDD(19)  = PVDDQ_ABC
  VTT(1)  = PVTT_ABC
  EVENT_N  = FM_DIMM_EVENT_COD_N
  A0  = M_A_MA<0>
  VDD(18)  = PVDDQ_ABC
  BA(0)  = M_A_BA<0>
  A16_RAS_N  = M_A_MA<16>
  VDD(17)  = PVDDQ_ABC
  S0_N  = M_A_CS_N<4>
  VDD(16)  = PVDDQ_ABC
  A15_CAS_N  = M_A_MA<15>
  ODT(0)  = M_A_ODT<2>
  VDD(15)  = PVDDQ_ABC
  S1_N  = M_A_CS_N<5>
  VDD(14)  = PVDDQ_ABC
  ODT(1)  = M_A_ODT<3>
  VDD(13)  = PVDDQ_ABC
  S2_N_C(0)  = M_A_CS_N<6>
  VSS(67)  = GND
  DQ(36)  = M_A_DQ<36>
  VSS(66)  = GND
  DQ(32)  = M_A_DQ<32>
  VSS(65)  = GND
  DQS13P  = M_A_DQS_DP<13>
  DQS13N  = M_A_DQS_DN<13>
  VSS(64)  = GND
  DQ(38)  = M_A_DQ<38>
  VSS(63)  = GND
  DQ(34)  = M_A_DQ<34>
  VSS(62)  = GND
  DQ(44)  = M_A_DQ<44>
  VSS(61)  = GND
  DQ(40)  = M_A_DQ<40>
  VSS(60)  = GND
  DQS14P  = M_A_DQS_DP<14>
  DQS14N  = M_A_DQS_DN<14>
  VSS(59)  = GND
  DQ(46)  = M_A_DQ<46>
  VSS(58)  = GND
  DQ(42)  = M_A_DQ<42>
  VSS(57)  = GND
  DQ(52)  = M_A_DQ<52>
  VSS(56)  = GND
  DQ(48)  = M_A_DQ<48>
  VSS(55)  = GND
  DQS15P  = M_A_DQS_DP<15>
  DQS15N  = M_A_DQS_DN<15>
  VSS(54)  = GND
  DQ(54)  = M_A_DQ<54>
  VSS(53)  = GND
  DQ(50)  = M_A_DQ<50>
  VSS(52)  = GND
  DQ(60)  = M_A_DQ<60>
  VSS(51)  = GND
  DQ(56)  = M_A_DQ<56>
  VSS(50)  = GND
  DQS16P  = M_A_DQS_DP<16>
  DQS16N  = M_A_DQS_DN<16>
  VSS(49)  = GND
  DQ(62)  = M_A_DQ<62>
  VSS(48)  = GND
  DQ(58)  = M_A_DQ<58>
  VSS(47)  = GND
  SA(0)  = PVPP_ABC
  SA(1)  = GND
  SCL  = SMB_DDR_ABC_VPP_SCL
  VPP(4)  = PVPP_ABC
  VPP(3)  = PVPP_ABC
  RFU(2)  = TP_CH_A_DIMM_A1_RFU_2
  \12v\(0)  = P12V_NVDIMM_ABC
  VREFCA  = M_A_VREF
  VSS(46)  = GND
  DQ(5)  = M_A_DQ<5>
  VSS(45)  = GND
  DQ(1)  = M_A_DQ<1>
  VSS(44)  = GND
  DQS0N  = M_A_DQS_DN<0>
  DQS0P  = M_A_DQS_DP<0>
  VSS(43)  = GND
  DQ(7)  = M_A_DQ<7>
  VSS(42)  = GND
  DQ(3)  = M_A_DQ<3>
  VSS(41)  = GND
  DQ(13)  = M_A_DQ<13>
  VSS(40)  = GND
  DQ(9)  = M_A_DQ<9>
  VSS(39)  = GND
  DQS1N  = M_A_DQS_DN<1>
  DQS1P  = M_A_DQS_DP<1>
  VSS(38)  = GND
  DQ(15)  = M_A_DQ<15>
  VSS(37)  = GND
  DQ(11)  = M_A_DQ<11>
  VSS(36)  = GND
  DQ(21)  = M_A_DQ<21>
  VSS(35)  = GND
  DQ(17)  = M_A_DQ<17>
  VSS(34)  = GND
  DQS2N  = M_A_DQS_DN<2>
  DQS2P  = M_A_DQS_DP<2>
  VSS(33)  = GND
  DQ(23)  = M_A_DQ<23>
  VSS(32)  = GND
  DQ(19)  = M_A_DQ<19>
  VSS(31)  = GND
  DQ(29)  = M_A_DQ<29>
  VSS(30)  = GND
  DQ(25)  = M_A_DQ<25>
  VSS(29)  = GND
  DQS3N  = M_A_DQS_DN<3>
  DQS3P  = M_A_DQS_DP<3>
  VSS(28)  = GND
  DQ(31)  = M_A_DQ<31>
  VSS(27)  = GND
  DQ(27)  = M_A_DQ<27>
  VSS(26)  = GND
  CB(5)  = M_A_ECC<5>
  VSS(25)  = GND
  CB(1)  = M_A_ECC<1>
  VSS(24)  = GND
  DQS8N  = M_A_DQS_DN<8>
  DQS8P  = M_A_DQS_DP<8>
  VSS(23)  = GND
  CB(7)  = M_A_ECC<7>
  VSS(22)  = GND
  CB(3)  = M_A_ECC<3>
  VSS(21)  = GND
  CKE(1)  = M_A_CKE<3>
  VDD(12)  = PVDDQ_ABC
  RFU(0)  = TP_CH_A_DIMM_A1_RFU_0
  VDD(11)  = PVDDQ_ABC
  BG(1)  = M_A_BG<1>
  ALERT_N  = M_A_ALERT_N
  VDD(10)  = PVDDQ_ABC
  A11  = M_A_MA<11>
  A7  = M_A_MA<7>
  VDD(9)  = PVDDQ_ABC
  A5  = M_A_MA<5>
  A4  = M_A_MA<4>
  VDD(8)  = PVDDQ_ABC
  A2  = M_A_MA<2>
  VDD(7)  = PVDDQ_ABC
  CK1P  = M_A_CLK_DP<3>
  CK1N  = M_A_CLK_DN<3>
  VDD(6)  = PVDDQ_ABC
  VTT(0)  = PVTT_ABC
  PAR  = M_A_PAR
  VDD(5)  = PVDDQ_ABC
  BA(1)  = M_A_BA<1>
  A10  = M_A_MA<10>
  VDD(4)  = PVDDQ_ABC
  RFU(1)  = TP_CH_A_DIMM_A1_RFU_1
  A14_WE_N  = M_A_MA<14>
  VDD(3)  = PVDDQ_ABC
  SAVE_N_NC  = FM_ADR_COMPLETE_ABC_N
  VDD(2)  = PVDDQ_ABC
  A13  = M_A_MA<13>
  VDD(1)  = PVDDQ_ABC
  A17  = M_A_MA<17>
  C(2)  = M_A_C<2>
  VDD(0)  = PVDDQ_ABC
  S3_N_C(1)  = M_A_CS_N<7>
  SA(2)  = GND
  VSS(20)  = GND
  DQ(37)  = M_A_DQ<37>
  VSS(19)  = GND
  DQ(33)  = M_A_DQ<33>
  VSS(18)  = GND
  DQS4N  = M_A_DQS_DN<4>
  DQS4P  = M_A_DQS_DP<4>
  VSS(17)  = GND
  DQ(39)  = M_A_DQ<39>
  VSS(16)  = GND
  DQ(35)  = M_A_DQ<35>
  VSS(15)  = GND
  DQ(45)  = M_A_DQ<45>
  VSS(14)  = GND
  DQ(41)  = M_A_DQ<41>
  VSS(13)  = GND
  DQS5N  = M_A_DQS_DN<5>
  DQS5P  = M_A_DQS_DP<5>
  VSS(12)  = GND
  DQ(47)  = M_A_DQ<47>
  VSS(11)  = GND
  DQ(43)  = M_A_DQ<43>
  VSS(10)  = GND
  DQ(53)  = M_A_DQ<53>
  VSS(9)  = GND
  DQ(49)  = M_A_DQ<49>
  VSS(8)  = GND
  DQS6N  = M_A_DQS_DN<6>
  DQS6P  = M_A_DQS_DP<6>
  VSS(7)  = GND
  DQ(55)  = M_A_DQ<55>
  VSS(6)  = GND
  DQ(51)  = M_A_DQ<51>
  VSS(5)  = GND
  DQ(61)  = M_A_DQ<61>
  VSS(4)  = GND
  DQ(57)  = M_A_DQ<57>
  VSS(3)  = GND
  DQS7N  = M_A_DQS_DN<7>
  DQS7P  = M_A_DQS_DP<7>
  VSS(2)  = GND
  DQ(63)  = M_A_DQ<63>
  VSS(1)  = GND
  DQ(59)  = M_A_DQ<59>
  VSS(0)  = GND
  VDDSPD  = PVPP_ABC
  SDA  = SMB_DDR_ABC_VPP_SDA
  VPP(1)  = PVPP_ABC
  VPP(0)  = PVPP_ABC
  VPP(2)  = PVPP_ABC

(kicad_pcb
	(version 20260206)
	(generator "pcbnew")
	(generator_version "10.0")
	(general
		(thickness 1.6)
		(legacy_teardrops no)
	)
	(paper "A4")
	(title_block
		(title "Wiwynn_Tioga_Pass_MB.brd")
		(comment 1 "Tioga Pass / footprint 3283 of 4770 (J6T1), pads 101-151 of 291")
	)
	(layers
		(0 "F.Cu" signal "TOP")
		(4 "In1.Cu" signal "L2GND")
		(6 "In2.Cu" signal "L3")
		(8 "In3.Cu" signal "L4GND")
		(10 "In4.Cu" signal "L5")
		(12 "In5.Cu" signal "L6GND")
		(14 "In6.Cu" signal "L7VCC")
		(16 "In7.Cu" signal "L8VCC")
		(18 "In8.Cu" signal "L9GND")
		(20 "In9.Cu" signal "L10")
		(22 "In10.Cu" signal "L11GND")
		(24 "In11.Cu" signal "L12")
		(26 "In12.Cu" signal "L13GND")
		(2 "B.Cu" signal "BOTTOM")
		(9 "F.Adhes" user "F.Adhesive")
		(11 "B.Adhes" user "B.Adhesive")
		(13 "F.Paste" user "Package Geometry/Pastemask Top")
		(15 "B.Paste" user "Package Geometry/Pastemask Bottom")
		(5 "F.SilkS" user "Ref Des/Silkscreen Top")
		(7 "B.SilkS" user "Ref Des/Silkscreen Bottom")
		(1 "F.Mask" user "Board Geometry/Soldermask Top")
		(3 "B.Mask" user "Board Geometry/Soldermask Bottom")
		(17 "Dwgs.User" user "User.Drawings")
		(19 "Cmts.User" user "User.Comments")
		(21 "Eco1.User" user "User.Eco1")
		(23 "Eco2.User" user "User.Eco2")
		(25 "Edge.Cuts" user "Board Geometry/Outline")
		(27 "Margin" user)
		(31 "F.CrtYd" user "Package Geometry/Place Bound Top")
		(29 "B.CrtYd" user "Package Geometry/Place Bound Bottom")
		(35 "F.Fab" user "Ref Des/Assembly Top")
		(33 "B.Fab" user "Ref Des/Assembly Bottom")
	)
	(footprint ""
		(layer "B.Cu")
		(at 194.700398 -24.824182 90)
		(property "Reference" "J6T1"
			(at 2.200148 39.23411 0)
			(unlocked yes)
			(layer "B.SilkS")
			(effects
				(font
					(size 0.7874 0.5842)
					(thickness 0.1524)
				)
				(justify left mirror)
			)
		)
		(property "Value" ""
			(at 0 0 90)
			(layer "B.Fab")
			(effects
				(font
					(size 1.27 1.27)
				)
				(justify mirror)
			)
		)
		(duplicate_pad_numbers_are_jumpers no)
		(pad "98" smd rect
			(at 0 87.54999 270)
			(size 1.8034 0.508)
			(layers "B.Cu" "B.Mask" "B.Paste")
			(net "GND")
		)
		(pad "99" smd rect
			(at 0 88.399874 270)
			(size 1.8034 0.508)
			(layers "B.Cu" "B.Mask" "B.Paste")
			(net "M_A_DQS_DP<13>")
		)
		(pad "100" smd rect
			(at 0 89.250012 270)
			(size 1.8034 0.508)
			(layers "B.Cu" "B.Mask" "B.Paste")
			(net "M_A_DQS_DN<13>")
		)
		(pad "101" smd rect
			(at 0 90.099896 270)
			(size 1.8034 0.508)
			(layers "B.Cu" "B.Mask" "B.Paste")
			(net "GND")
		)
		(pad "102" smd rect
			(at 0 90.950034 270)
			(size 1.8034 0.508)
			(layers "B.Cu" "B.Mask" "B.Paste")
			(net "M_A_DQ<38>")
		)
		(pad "103" smd rect
			(at 0 91.799918 270)
			(size 1.8034 0.508)
			(layers "B.Cu" "B.Mask" "B.Paste")
			(net "GND")
		)
		(pad "104" smd rect
			(at 0 92.650056 270)
			(size 1.8034 0.508)
			(layers "B.Cu" "B.Mask" "B.Paste")
			(net "M_A_DQ<34>")
		)
		(pad "105" smd rect
			(at 0 93.49994 270)
			(size 1.8034 0.508)
			(layers "B.Cu" "B.Mask" "B.Paste")
			(net "GND")
		)
		(pad "106" smd rect
			(at 0 94.350078 270)
			(size 1.8034 0.508)
			(layers "B.Cu" "B.Mask" "B.Paste")
			(net "M_A_DQ<44>")
		)
		(pad "107" smd rect
			(at 0 95.199962 270)
			(size 1.8034 0.508)
			(layers "B.Cu" "B.Mask" "B.Paste")
			(net "GND")
		)
		(pad "108" smd rect
			(at 0 96.0501 270)
			(size 1.8034 0.508)
			(layers "B.Cu" "B.Mask" "B.Paste")
			(net "M_A_DQ<40>")
		)
		(pad "109" smd rect
			(at 0 96.899984 270)
			(size 1.8034 0.508)
			(layers "B.Cu" "B.Mask" "B.Paste")
			(net "GND")
		)
		(pad "110" smd rect
			(at 0 97.750122 270)
			(size 1.8034 0.508)
			(layers "B.Cu" "B.Mask" "B.Paste")
			(net "M_A_DQS_DP<14>")
		)
		(pad "111" smd rect
			(at 0 98.600006 270)
			(size 1.8034 0.508)
			(layers "B.Cu" "B.Mask" "B.Paste")
			(net "M_A_DQS_DN<14>")
		)
		(pad "112" smd rect
			(at 0 99.44989 270)
			(size 1.8034 0.508)
			(layers "B.Cu" "B.Mask" "B.Paste")
			(net "GND")
		)
		(pad "113" smd rect
			(at 0 100.300028 270)
			(size 1.8034 0.508)
			(layers "B.Cu" "B.Mask" "B.Paste")
			(net "M_A_DQ<46>")
		)
		(pad "114" smd rect
			(at 0 101.149912 270)
			(size 1.8034 0.508)
			(layers "B.Cu" "B.Mask" "B.Paste")
			(net "GND")
		)
		(pad "115" smd rect
			(at 0 102.00005 270)
			(size 1.8034 0.508)
			(layers "B.Cu" "B.Mask" "B.Paste")
			(net "M_A_DQ<42>")
		)
		(pad "116" smd rect
			(at 0 102.849934 270)
			(size 1.8034 0.508)
			(layers "B.Cu" "B.Mask" "B.Paste")
			(net "GND")
		)
		(pad "117" smd rect
			(at 0 103.700072 270)
			(size 1.8034 0.508)
			(layers "B.Cu" "B.Mask" "B.Paste")
			(net "M_A_DQ<52>")
		)
		(pad "118" smd rect
			(at 0 104.549956 270)
			(size 1.8034 0.508)
			(layers "B.Cu" "B.Mask" "B.Paste")
			(net "GND")
		)
		(pad "119" smd rect
			(at 0 105.400094 270)
			(size 1.8034 0.508)
			(layers "B.Cu" "B.Mask" "B.Paste")
			(net "M_A_DQ<48>")
		)
		(pad "120" smd rect
			(at 0 106.249978 270)
			(size 1.8034 0.508)
			(layers "B.Cu" "B.Mask" "B.Paste")
			(net "GND")
		)
		(pad "121" smd rect
			(at 0 107.100116 270)
			(size 1.8034 0.508)
			(layers "B.Cu" "B.Mask" "B.Paste")
			(net "M_A_DQS_DP<15>")
		)
		(pad "122" smd rect
			(at 0 107.95 270)
			(size 1.8034 0.508)
			(layers "B.Cu" "B.Mask" "B.Paste")
			(net "M_A_DQS_DN<15>")
		)
		(pad "123" smd rect
			(at 0 108.799884 270)
			(size 1.8034 0.508)
			(layers "B.Cu" "B.Mask" "B.Paste")
			(net "GND")
		)
		(pad "124" smd rect
			(at 0 109.650022 270)
			(size 1.8034 0.508)
			(layers "B.Cu" "B.Mask" "B.Paste")
			(net "M_A_DQ<54>")
		)
		(pad "125" smd rect
			(at 0 110.499906 270)
			(size 1.8034 0.508)
			(layers "B.Cu" "B.Mask" "B.Paste")
			(net "GND")
		)
		(pad "126" smd rect
			(at 0 111.350044 270)
			(size 1.8034 0.508)
			(layers "B.Cu" "B.Mask" "B.Paste")
			(net "M_A_DQ<50>")
		)
		(pad "127" smd rect
			(at 0 112.199928 270)
			(size 1.8034 0.508)
			(layers "B.Cu" "B.Mask" "B.Paste")
			(net "GND")
		)
		(pad "128" smd rect
			(at 0 113.050066 270)
			(size 1.8034 0.508)
			(layers "B.Cu" "B.Mask" "B.Paste")
			(net "M_A_DQ<60>")
		)
		(pad "129" smd rect
			(at 0 113.89995 270)
			(size 1.8034 0.508)
			(layers "B.Cu" "B.Mask" "B.Paste")
			(net "GND")
		)
		(pad "130" smd rect
			(at 0 114.750088 270)
			(size 1.8034 0.508)
			(layers "B.Cu" "B.Mask" "B.Paste")
			(net "M_A_DQ<56>")
		)
		(pad "131" smd rect
			(at 0 115.599972 270)
			(size 1.8034 0.508)
			(layers "B.Cu" "B.Mask" "B.Paste")
			(net "GND")
		)
		(pad "132" smd rect
			(at 0 116.45011 270)
			(size 1.8034 0.508)
			(layers "B.Cu" "B.Mask" "B.Paste")
			(net "M_A_DQS_DP<16>")
		)
		(pad "133" smd rect
			(at 0 117.299994 270)
			(size 1.8034 0.508)
			(layers "B.Cu" "B.Mask" "B.Paste")
			(net "M_A_DQS_DN<16>")
		)
		(pad "134" smd rect
			(at 0 118.149878 270)
			(size 1.8034 0.508)
			(layers "B.Cu" "B.Mask" "B.Paste")
			(net "GND")
		)
		(pad "135" smd rect
			(at 0 119.000016 270)
			(size 1.8034 0.508)
			(layers "B.Cu" "B.Mask" "B.Paste")
			(net "M_A_DQ<62>")
		)
		(pad "136" smd rect
			(at 0 119.8499 270)
			(size 1.8034 0.508)
			(layers "B.Cu" "B.Mask" "B.Paste")
			(net "GND")
		)
		(pad "137" smd rect
			(at 0 120.700038 270)
			(size 1.8034 0.508)
			(layers "B.Cu" "B.Mask" "B.Paste")
			(net "M_A_DQ<58>")
		)
		(pad "138" smd rect
			(at 0 121.549922 270)
			(size 1.8034 0.508)
			(layers "B.Cu" "B.Mask" "B.Paste")
			(net "GND")
		)
		(pad "139" smd rect
			(at 0 122.40006 270)
			(size 1.8034 0.508)
			(layers "B.Cu" "B.Mask" "B.Paste")
			(net "PVPP_ABC")
		)
		(pad "140" smd rect
			(at 0 123.249944 270)
			(size 1.8034 0.508)
			(layers "B.Cu" "B.Mask" "B.Paste")
			(net "GND")
		)
		(pad "141" smd rect
			(at 0 124.100082 270)
			(size 1.8034 0.508)
			(layers "B.Cu" "B.Mask" "B.Paste")
			(net "SMB_DDR_ABC_VPP_SCL")
		)
		(pad "142" smd rect
			(at 0 124.949966 270)
			(size 1.8034 0.508)
			(layers "B.Cu" "B.Mask" "B.Paste")
			(net "PVPP_ABC")
		)
		(pad "143" smd rect
			(at 0 125.800104 270)
			(size 1.8034 0.508)
			(layers "B.Cu" "B.Mask" "B.Paste")
			(net "PVPP_ABC")
		)
		(pad "144" smd rect
			(at 0 126.649988 270)
			(size 1.8034 0.508)
			(layers "B.Cu" "B.Mask" "B.Paste")
			(net "TP_CH_A_DIMM_A1_RFU_2")
		)
		(pad "145" smd rect
			(at -4.59994 0 270)
			(size 1.8034 0.508)
			(layers "B.Cu" "B.Mask" "B.Paste")
			(net "P12V_NVDIMM_ABC")
		)
		(pad "146" smd rect
			(at -4.59994 0.849884 270)
			(size 1.8034 0.508)
			(layers "B.Cu" "B.Mask" "B.Paste")
			(net "M_A_VREF")
		)
		(pad "147" smd rect
			(at -4.59994 1.700022 270)
			(size 1.8034 0.508)
			(layers "B.Cu" "B.Mask" "B.Paste")
			(net "GND")
		)
		(pad "148" smd rect
			(at -4.59994 2.549906 270)
			(size 1.8034 0.508)
			(layers "B.Cu" "B.Mask" "B.Paste")
			(net "M_A_DQ<5>")
		)
	)
)
